(kicad_pcb
	(version 20241229)
	(generator "pcbnew")
	(generator_version "9.0")
	(general
		(thickness 1.6642)
		(legacy_teardrops no)
	)
	(paper "A3")
	(title_block
		(title "PolarFire SoM")
		(date "2025-07-22")
		(rev "1.1.4")
		(company "Antmicro Ltd")
		(comment 1 "www.antmicro.com")
		(comment 9 "footprints 36-39 of 470")
	)
	(layers
		(0 "F.Cu" mixed)
		(4 "In1.Cu" power)
		(6 "In2.Cu" signal)
		(8 "In3.Cu" power)
		(10 "In4.Cu" signal)
		(12 "In5.Cu" power)
		(14 "In6.Cu" power)
		(16 "In7.Cu" signal)
		(18 "In8.Cu" power)
		(20 "In9.Cu" signal)
		(22 "In10.Cu" power)
		(24 "In11.Cu" signal)
		(26 "In12.Cu" signal)
		(2 "B.Cu" mixed)
		(9 "F.Adhes" user "F.Adhesive")
		(11 "B.Adhes" user "B.Adhesive")
		(13 "F.Paste" user)
		(15 "B.Paste" user)
		(5 "F.SilkS" user "F.Silkscreen")
		(7 "B.SilkS" user "B.Silkscreen")
		(1 "F.Mask" user)
		(3 "B.Mask" user)
		(17 "Dwgs.User" user "User.Drawings")
		(19 "Cmts.User" user "User.Comments")
		(21 "Eco1.User" user "User.Eco1")
		(23 "Eco2.User" user "User.Eco2")
		(25 "Edge.Cuts" user)
		(27 "Margin" user)
		(31 "F.CrtYd" user "F.Courtyard")
		(29 "B.CrtYd" user "B.Courtyard")
		(35 "F.Fab" user)
		(33 "B.Fab" user)
	)
	(footprint "antmicro-footprints:C_0402_1005Metric"
		(layer "F.Cu")
		(at 184.975 142.9875 -90)
		(descr "Capacitor SMD 0402")
		(tags "capacitor SMD 0402")
		(property "Reference" "C103"
			(at 0.8625 -0.485 90)
			(layer "F.SilkS")
			(effects
				(font
					(size 0.7 0.7)
					(thickness 0.15)
				)
				(justify right bottom)
			)
		)
		(property "Value" "C_22u_0402"
			(at -1.022927 2.155213 90)
			(layer "F.Fab")
			(hide yes)
			(effects
				(font
					(size 0.7 0.7)
					(thickness 0.15)
				)
				(justify right bottom)
			)
		)
		(property "Datasheet" "https://www.murata.com/products/productdetail?partno=GRM158R60J226ME01%23"
			(at 0 0 270)
			(layer "F.Fab")
			(hide yes)
			(effects
				(font
					(size 1.27 1.27)
					(thickness 0.15)
				)
			)
		)
		(property "Description" "SMD Multilayer Ceramic Capacitor, 22 uF, 4 V, 0402 [1005 Metric], X6S"
			(at 0 0 270)
			(layer "F.Fab")
			(hide yes)
			(effects
				(font
					(size 1.27 1.27)
					(thickness 0.15)
				)
			)
		)
		(property "Author" "Antmicro"
			(at 41.9875 327.9625 0)
			(layer "F.Fab")
			(hide yes)
			(effects
				(font
					(size 1 1)
					(thickness 0.15)
				)
			)
		)
		(property "Dielectric" ""
			(at 41.9875 327.9625 0)
			(layer "F.Fab")
			(hide yes)
			(effects
				(font
					(size 1 1)
					(thickness 0.15)
				)
			)
		)
		(property "License" "Apache-2.0"
			(at 41.9875 327.9625 0)
			(layer "F.Fab")
			(hide yes)
			(effects
				(font
					(size 1 1)
					(thickness 0.15)
				)
			)
		)
		(property "MPN" "GRM158R60J226ME01D"
			(at 41.9875 327.9625 0)
			(layer "F.Fab")
			(hide yes)
			(effects
				(font
					(size 1 1)
					(thickness 0.15)
				)
			)
		)
		(property "Manufacturer" "Murata"
			(at 41.9875 327.9625 0)
			(layer "F.Fab")
			(hide yes)
			(effects
				(font
					(size 1 1)
					(thickness 0.15)
				)
			)
		)
		(property "Public" ""
			(at 41.9875 327.9625 0)
			(layer "F.Fab")
			(hide yes)
			(effects
				(font
					(size 1 1)
					(thickness 0.15)
				)
			)
		)
		(property "Val" "22u"
			(at 41.9875 327.9625 0)
			(layer "F.Fab")
			(hide yes)
			(effects
				(font
					(size 1 1)
					(thickness 0.15)
				)
			)
		)
		(property "Voltage" ""
			(at 41.9875 327.9625 0)
			(layer "F.Fab")
			(hide yes)
			(effects
				(font
					(size 1 1)
					(thickness 0.15)
				)
			)
		)
		(sheetname "/Supply/")
		(sheetfile "supply.kicad_sch")
		(attr smd)
		(fp_rect
			(start -0.925 -0.47)
			(end 0.925 0.47)
			(stroke
				(width 0.05)
				(type default)
			)
			(fill no)
			(layer "F.CrtYd")
		)
		(fp_line
			(start -0.494 0.248)
			(end -0.494 -0.25)
			(stroke
				(width 0.15)
				(type solid)
			)
			(layer "F.Fab")
		)
		(fp_line
			(start 0.504 0.248)
			(end -0.494 0.248)
			(stroke
				(width 0.15)
				(type solid)
			)
			(layer "F.Fab")
		)
		(fp_line
			(start -0.494 -0.25)
			(end 0.504 -0.25)
			(stroke
				(width 0.15)
				(type solid)
			)
			(layer "F.Fab")
		)
		(fp_line
			(start 0.504 -0.25)
			(end 0.504 0.248)
			(stroke
				(width 0.15)
				(type solid)
			)
			(layer "F.Fab")
		)
		(fp_text user "License: Apache-2.0"
			(at -0.939 5.799 270)
			(layer "F.Fab")
			(effects
				(font
					(size 0.7 0.7)
					(thickness 0.15)
				)
				(justify left bottom)
			)
		)
		(fp_text user "Author: Antmicro"
			(at -0.939 3.399 270)
			(layer "F.Fab")
			(effects
				(font
					(size 0.7 0.7)
					(thickness 0.15)
				)
				(justify left bottom)
			)
		)
		(fp_text user "${REFERENCE}"
			(at -0.939 4.599 270)
			(layer "F.Fab")
			(effects
				(font
					(size 0.7 0.7)
					(thickness 0.15)
				)
				(justify left bottom)
			)
		)
		(pad "1" smd roundrect
			(at -0.48 0 270)
			(size 0.59 0.64)
			(layers "F.Cu" "F.Mask" "F.Paste")
			(roundrect_rratio 0.25)
			(net 417 "GND")
			(pintype "passive")
		)
		(pad "2" smd roundrect
			(at 0.48 0 270)
			(size 0.59 0.64)
			(layers "F.Cu" "F.Mask" "F.Paste")
			(roundrect_rratio 0.25)
			(net 409 "/Supply/SENSE4_P")
			(pintype "passive")
		)
	)
	(footprint "antmicro-footprints:UQFN-10_1.4x1.8x0.5mm_P0.4mm"
		(layer "F.Cu")
		(at 215.983 153.0715)
		(property "Reference" "U23"
			(at 1.527 -0.3615 90)
			(layer "F.SilkS")
			(effects
				(font
					(size 0.7 0.7)
					(thickness 0.15)
				)
				(justify left bottom)
			)
		)
		(property "Value" "PI3USB102GZLEX"
			(at 0 2.4 0)
			(layer "F.Fab")
			(hide yes)
			(effects
				(font
					(size 0.7 0.7)
					(thickness 0.15)
				)
				(justify left bottom)
			)
		)
		(property "Datasheet" "https://www.diodes.com/assets/Datasheets/PI3USB102G.pdf"
			(at 0 0 0)
			(layer "F.Fab")
			(hide yes)
			(effects
				(font
					(size 1.27 1.27)
					(thickness 0.15)
				)
			)
		)
		(property "Description" "USB Switch IC 1 Channel 10-TQFN (1.3x1.6)"
			(at 0 0 0)
			(layer "F.Fab")
			(hide yes)
			(effects
				(font
					(size 1.27 1.27)
					(thickness 0.15)
				)
			)
		)
		(property "Author" "Antmicro"
			(at 0 0 0)
			(layer "F.Fab")
			(hide yes)
			(effects
				(font
					(size 1 1)
					(thickness 0.15)
				)
			)
		)
		(property "License" "Apache-2.0"
			(at 0 0 0)
			(layer "F.Fab")
			(hide yes)
			(effects
				(font
					(size 1 1)
					(thickness 0.15)
				)
			)
		)
		(property "MPN" "PI3USB102GZLEX"
			(at 0 0 0)
			(layer "F.Fab")
			(hide yes)
			(effects
				(font
					(size 1 1)
					(thickness 0.15)
				)
			)
		)
		(property "Manufacturer" "Diodes Incorporated"
			(at 0 0 0)
			(layer "F.Fab")
			(hide yes)
			(effects
				(font
					(size 1 1)
					(thickness 0.15)
				)
			)
		)
		(property ki_fp_filters "MSOP*3x3mm*P0.5mm*")
		(sheetname "/USB/")
		(sheetfile "usb.kicad_sch")
		(attr smd)
		(fp_line
			(start -0.7305 -0.552)
			(end -1.2005 -0.552)
			(stroke
				(width 0.15)
				(type solid)
			)
			(layer "F.SilkS")
		)
		(fp_line
			(start -0.7305 -0.552)
			(end -0.7305 -0.93)
			(stroke
				(width 0.15)
				(type solid)
			)
			(layer "F.SilkS")
		)
		(fp_circle
			(center -1.0515 -1.151)
			(end -0.9805 -1.151)
			(stroke
				(width 0.15)
				(type solid)
			)
			(fill no)
			(layer "F.SilkS")
		)
		(fp_rect
			(start -1.3 -1.5)
			(end 1.3 1.5)
			(stroke
				(width 0.05)
				(type solid)
			)
			(fill no)
			(layer "F.CrtYd")
		)
		(fp_line
			(start -0.7 -0.4)
			(end -0.175 -0.925)
			(stroke
				(width 0.15)
				(type solid)
			)
			(layer "F.Fab")
		)
		(fp_line
			(start -0.7 0.93)
			(end -0.7 -0.4)
			(stroke
				(width 0.15)
				(type solid)
			)
			(layer "F.Fab")
		)
		(fp_line
			(start -0.175 -0.925)
			(end 0.7295 -0.925)
			(stroke
				(width 0.15)
				(type solid)
			)
			(layer "F.Fab")
		)
		(fp_line
			(start 0.725 0.93)
			(end -0.7 0.93)
			(stroke
				(width 0.15)
				(type solid)
			)
			(layer "F.Fab")
		)
		(fp_line
			(start 0.7295 -0.925)
			(end 0.725 0.93)
			(stroke
				(width 0.15)
				(type solid)
			)
			(layer "F.Fab")
		)
		(fp_text user "Author: Antmicro"
			(at -0.657 5.7 0)
			(layer "F.Fab")
			(effects
				(font
					(size 0.7 0.7)
					(thickness 0.15)
				)
				(justify left bottom)
			)
		)
		(fp_text user "License: Apache-2.0"
			(at -0.657 6.9 0)
			(layer "F.Fab")
			(effects
				(font
					(size 0.7 0.7)
					(thickness 0.15)
				)
				(justify left bottom)
			)
		)
		(fp_text user "${REFERENCE}"
			(at -0.657 4.498 0)
			(layer "F.Fab")
			(effects
				(font
					(size 0.7 0.7)
					(thickness 0.15)
				)
				(justify left bottom)
			)
		)
		(pad "1" smd roundrect
			(at -0.6445 -0.2)
			(size 0.81 0.22)
			(layers "F.Cu" "F.Mask" "F.Paste")
			(roundrect_rratio 0.25)
			(net 499 "/USB/USB_P")
			(pinfunction "D+")
			(pintype "bidirectional")
		)
		(pad "2" smd roundrect
			(at -0.6445 0.2)
			(size 0.81 0.22)
			(layers "F.Cu" "F.Mask" "F.Paste")
			(roundrect_rratio 0.25)
			(net 498 "/USB/USB_N")
			(pinfunction "D-")
			(pintype "bidirectional")
		)
		(pad "3" smd roundrect
			(at -0.4015 0.844 270)
			(size 0.81 0.22)
			(layers "F.Cu" "F.Mask" "F.Paste")
			(roundrect_rratio 0.25)
			(net 417 "GND")
			(pinfunction "GND")
			(pintype "power_in")
		)
		(pad "4" smd roundrect
			(at 0.0005 0.844 270)
			(size 0.81 0.22)
			(layers "F.Cu" "F.Mask" "F.Paste")
			(roundrect_rratio 0.25)
			(net 512 "/USB/USB_UP_N")
			(pinfunction "D1-")
			(pintype "bidirectional")
		)
		(pad "5" smd roundrect
			(at 0.3995 0.844 270)
			(size 0.81 0.22)
			(layers "F.Cu" "F.Mask" "F.Paste")
			(roundrect_rratio 0.25)
			(net 513 "/USB/USB_UP_P")
			(pinfunction "D1+")
			(pintype "bidirectional")
		)
		(pad "6" smd roundrect
			(at 0.6455 0.2)
			(size 0.81 0.22)
			(layers "F.Cu" "F.Mask" "F.Paste")
			(roundrect_rratio 0.25)
			(net 510 "/USB/USB_BYP_N")
			(pinfunction "D2-")
			(pintype "bidirectional")
		)
		(pad "7" smd roundrect
			(at 0.6455 -0.2)
			(size 0.81 0.22)
			(layers "F.Cu" "F.Mask" "F.Paste")
			(roundrect_rratio 0.25)
			(net 511 "/USB/USB_BYP_P")
			(pinfunction "D2+")
			(pintype "bidirectional")
		)
		(pad "8" smd roundrect
			(at 0.3995 -0.847 270)
			(size 0.81 0.22)
			(layers "F.Cu" "F.Mask" "F.Paste")
			(roundrect_rratio 0.25)
			(net 417 "GND")
			(pinfunction "~{OE}")
			(pintype "input")
		)
		(pad "9" smd roundrect
			(at 0.0005 -0.847 270)
			(size 0.81 0.22)
			(layers "F.Cu" "F.Mask" "F.Paste")
			(roundrect_rratio 0.25)
			(net 50 "+3V3")
			(pinfunction "V_{DD}")
			(pintype "power_in")
		)
		(pad "10" smd roundrect
			(at -0.4015 -0.847 270)
			(size 0.81 0.22)
			(layers "F.Cu" "F.Mask" "F.Paste")
			(roundrect_rratio 0.25)
			(net 62 "USB_OTG_ID")
			(pinfunction "SEL")
			(pintype "input")
		)
	)
	(footprint "antmicro-footprints:FB_0402_1005Metric"
		(layer "F.Cu")
		(at 208.085 146.8)
		(descr "Ferrite Bead SMD 0402")
		(tags "ferrite bead SMD 0402")
		(property "Reference" "FB2"
			(at -5.135 7.515 90)
			(layer "F.SilkS")
			(effects
				(font
					(size 0.7 0.7)
					(thickness 0.15)
				)
				(justify left bottom)
			)
		)
		(property "Value" "FB_120Z_1.2A_TDK-MPZ_0402"
			(at 0 1.4 0)
			(layer "F.Fab")
			(hide yes)
			(effects
				(font
					(size 0.7 0.7)
					(thickness 0.15)
				)
				(justify left bottom)
			)
		)
		(property "Datasheet" "https://product.tdk.com/en/search/emc/emc/beads/info?part_no=MPZ1005S121CT000"
			(at 0 0 0)
			(layer "F.Fab")
			(hide yes)
			(effects
				(font
					(size 1.27 1.27)
					(thickness 0.15)
				)
			)
		)
		(property "Description" "Ferrite Bead, 0402 [1005 Metric], 120 ohm, 1.2A, MPZ, 0.06 ohm, ± 25%, DC Power line"
			(at 0 0 0)
			(layer "F.Fab")
			(hide yes)
			(effects
				(font
					(size 1.27 1.27)
					(thickness 0.15)
				)
			)
		)
		(property "Author" "Antmicro"
			(at 0 0 0)
			(layer "F.Fab")
			(hide yes)
			(effects
				(font
					(size 1 1)
					(thickness 0.15)
				)
			)
		)
		(property "Current" ""
			(at 0 0 0)
			(layer "F.Fab")
			(hide yes)
			(effects
				(font
					(size 1 1)
					(thickness 0.15)
				)
			)
		)
		(property "License" "Apache-2.0"
			(at 0 0 0)
			(layer "F.Fab")
			(hide yes)
			(effects
				(font
					(size 1 1)
					(thickness 0.15)
				)
			)
		)
		(property "MPN" "MPZ1005S121CT000"
			(at 0 0 0)
			(layer "F.Fab")
			(hide yes)
			(effects
				(font
					(size 1 1)
					(thickness 0.15)
				)
			)
		)
		(property "Manufacturer" "TDK"
			(at 0 0 0)
			(layer "F.Fab")
			(hide yes)
			(effects
				(font
					(size 1 1)
					(thickness 0.15)
				)
			)
		)
		(property "Public" ""
			(at 0 0 0)
			(layer "F.Fab")
			(hide yes)
			(effects
				(font
					(size 1 1)
					(thickness 0.15)
				)
			)
		)
		(property "Val" "120Z/1.2A"
			(at 0 0 0)
			(layer "F.Fab")
			(hide yes)
			(effects
				(font
					(size 1 1)
					(thickness 0.15)
				)
			)
		)
		(sheetname "/MIPI CrossLink/")
		(sheetfile "crosslink.kicad_sch")
		(attr smd)
		(fp_rect
			(start -0.925 -0.47)
			(end 0.925 0.47)
			(stroke
				(width 0.05)
				(type default)
			)
			(fill no)
			(layer "F.CrtYd")
		)
		(fp_rect
			(start -0.5 -0.25)
			(end 0.5 0.25)
			(stroke
				(width 0.15)
				(type solid)
			)
			(fill no)
			(layer "F.Fab")
		)
		(fp_text user "${REFERENCE}"
			(at -0.95 3.168 0)
			(layer "F.Fab")
			(effects
				(font
					(size 0.7 0.7)
					(thickness 0.15)
				)
				(justify left bottom)
			)
		)
		(fp_text user "License: Apache-2.0"
			(at -0.95 5.169 0)
			(layer "F.Fab")
			(effects
				(font
					(size 0.7 0.7)
					(thickness 0.15)
				)
				(justify left bottom)
			)
		)
		(fp_text user "Author: Antmicro"
			(at -0.95 4.169 0)
			(layer "F.Fab")
			(effects
				(font
					(size 0.7 0.7)
					(thickness 0.15)
				)
				(justify left bottom)
			)
		)
		(pad "1" smd roundrect
			(at -0.48 0)
			(size 0.59 0.64)
			(layers "F.Cu" "F.Mask" "F.Paste")
			(roundrect_rratio 0.25)
			(net 183 "/MIPI CrossLink/CL_VCCIO0")
			(pintype "passive")
		)
		(pad "2" smd roundrect
			(at 0.48 0)
			(size 0.59 0.64)
			(layers "F.Cu" "F.Mask" "F.Paste")
			(roundrect_rratio 0.25)
			(net 649 "VDD")
			(pintype "passive")
		)
	)
	(footprint "antmicro-footprints:R_0402_1005Metric"
		(layer "F.Cu")
		(at 185.05 121.45)
		(descr "Resistor SMD 0402")
		(tags "resistor SMD 0402")
		(property "Reference" "R90"
			(at 1.19 2.65 90)
			(layer "F.SilkS")
			(effects
				(font
					(size 0.7 0.7)
					(thickness 0.15)
				)
				(justify left bottom)
			)
		)
		(property "Value" "R_0R_0402"
			(at -1.011843 1.772047 0)
			(layer "F.Fab")
			(hide yes)
			(effects
				(font
					(size 0.7 0.7)
					(thickness 0.15)
				)
				(justify left bottom)
			)
		)
		(property "Datasheet" "https://industrial.panasonic.com/cdbs/www-data/pdf/RDA0000/AOA0000C301.pdf"
			(at 0 0 0)
			(layer "F.Fab")
			(hide yes)
			(effects
				(font
					(size 1.27 1.27)
					(thickness 0.15)
				)
			)
		)
		(property "Description" "SMD Chip Resistor, Jumper, 0 ohm, 100 mW, 0402 [1005 Metric], Thick Film, General Purpose"
			(at 0 0 0)
			(layer "F.Fab")
			(hide yes)
			(effects
				(font
					(size 1.27 1.27)
					(thickness 0.15)
				)
			)
		)
		(property "Author" "Antmicro"
			(at 0 0 0)
			(layer "F.Fab")
			(hide yes)
			(effects
				(font
					(size 1 1)
					(thickness 0.15)
				)
			)
		)
		(property "Current" "1A"
			(at 0 0 0)
			(layer "F.Fab")
			(hide yes)
			(effects
				(font
					(size 1 1)
					(thickness 0.15)
				)
			)
		)
		(property "License" "Apache-2.0"
			(at 0 0 0)
			(layer "F.Fab")
			(hide yes)
			(effects
				(font
					(size 1 1)
					(thickness 0.15)
				)
			)
		)
		(property "MPN" "ERJ2GE0R00X"
			(at 0 0 0)
			(layer "F.Fab")
			(hide yes)
			(effects
				(font
					(size 1 1)
					(thickness 0.15)
				)
			)
		)
		(property "Manufacturer" "Panasonic"
			(at 0 0 0)
			(layer "F.Fab")
			(hide yes)
			(effects
				(font
					(size 1 1)
					(thickness 0.15)
				)
			)
		)
		(property "Public" ""
			(at 0 0 0)
			(layer "F.Fab")
			(hide yes)
			(effects
				(font
					(size 1 1)
					(thickness 0.15)
				)
			)
		)
		(property "Tolerance" "~"
			(at 0 0 0)
			(layer "F.Fab")
			(hide yes)
			(effects
				(font
					(size 1 1)
					(thickness 0.15)
				)
			)
		)
		(property "Val" "0R"
			(at 0 0 0)
			(layer "F.Fab")
			(hide yes)
			(effects
				(font
					(size 1 1)
					(thickness 0.15)
				)
			)
		)
		(sheetname "/FPGA Config/")
		(sheetfile "fpga-config.kicad_sch")
		(attr smd dnp)
		(fp_rect
			(start -0.925 -0.47)
			(end 0.925 0.47)
			(stroke
				(width 0.05)
				(type default)
			)
			(fill no)
			(layer "F.CrtYd")
		)
		(fp_rect
			(start -0.5 -0.25)
			(end 0.5 0.25)
			(stroke
				(width 0.15)
				(type solid)
			)
			(fill no)
			(layer "F.Fab")
		)
		(fp_text user "${REFERENCE}"
			(at -0.95 3.168 0)
			(layer "F.Fab")
			(effects
				(font
					(size 0.7 0.7)
					(thickness 0.15)
				)
				(justify left bottom)
			)
		)
		(fp_text user "License: Apache-2.0"
			(at -0.95 5.169 0)
			(layer "F.Fab")
			(effects
				(font
					(size 0.7 0.7)
					(thickness 0.15)
				)
				(justify left bottom)
			)
		)
		(fp_text user "Author: Antmicro"
			(at -0.95 4.169 0)
			(layer "F.Fab")
			(effects
				(font
					(size 0.7 0.7)
					(thickness 0.15)
				)
				(justify left bottom)
			)
		)
		(pad "1" smd roundrect
			(at -0.48 0)
			(size 0.59 0.64)
			(layers "F.Cu" "F.Mask" "F.Paste")
			(roundrect_rratio 0.25)
			(net 189 "Net-(U1D-TDO)")
			(pintype "passive")
		)
		(pad "2" smd roundrect
			(at 0.48 0)
			(size 0.59 0.64)
			(layers "F.Cu" "F.Mask" "F.Paste")
			(roundrect_rratio 0.25)
			(net 192 "PF_TDO")
			(pintype "passive")
		)
	)
)
